(kicad_pcb
	(version 20260206)
	(generator "pcbnew")
	(generator_version "10.0")
	(general
		(thickness 1.6)
		(legacy_teardrops no)
	)
	(paper "A4")
	(title_block
		(title "dpb — 14545-sa.0730WZS0815.brd")
		(comment 1 "Honey Badger (Wiwynn) / footprints 88-94 of 1066")
	)
	(layers
		(0 "F.Cu" signal "TOP")
		(4 "In1.Cu" signal "L2GND")
		(6 "In2.Cu" signal "L3")
		(8 "In3.Cu" signal "L4VCC")
		(10 "In4.Cu" signal "L5VCC")
		(12 "In5.Cu" signal "L6")
		(14 "In6.Cu" signal "L7GND")
		(2 "B.Cu" signal "BOTTOM")
		(9 "F.Adhes" user "F.Adhesive")
		(11 "B.Adhes" user "B.Adhesive")
		(13 "F.Paste" user "Package Geometry/Pastemask Top")
		(15 "B.Paste" user "Package Geometry/Pastemask Bottom")
		(5 "F.SilkS" user "Ref Des/Silkscreen Top")
		(7 "B.SilkS" user "Ref Des/Silkscreen Bottom")
		(1 "F.Mask" user "Board Geometry/Soldermask Top")
		(3 "B.Mask" user "Board Geometry/Soldermask Bottom")
		(17 "Dwgs.User" user "User.Drawings")
		(19 "Cmts.User" user "User.Comments")
		(21 "Eco1.User" user "User.Eco1")
		(23 "Eco2.User" user "User.Eco2")
		(25 "Edge.Cuts" user "Board Geometry/Outline")
		(27 "Margin" user)
		(31 "F.CrtYd" user "Package Geometry/Place Bound Top")
		(29 "B.CrtYd" user "Package Geometry/Place Bound Bottom")
		(35 "F.Fab" user "Ref Des/Assembly Top")
		(33 "B.Fab" user "Ref Des/Assembly Bottom")
	)
	(footprint ""
		(layer "F.Cu")
		(at 19.176746 -466.7377 -90)
		(property "Reference" "R240"
			(at 0 0 270)
			(layer "F.SilkS")
			(hide yes)
			(effects
				(font
					(size 1.27 1.27)
				)
			)
		)
		(property "Value" "10KR2F-2-GP"
			(at 0.064008 -3.993896 270)
			(unlocked yes)
			(layer "F.Fab")
			(hide yes)
			(effects
				(font
					(size 1.016 1.016)
					(thickness 0.1524)
				)
			)
		)
		(property "Device Type" "R402H16"
			(at 0.064008 -5.517896 270)
			(unlocked yes)
			(layer "F.Fab")
			(hide yes)
			(effects
				(font
					(size 1.016 1.016)
					(thickness 0.1524)
				)
			)
		)
		(duplicate_pad_numbers_are_jumpers no)
		(fp_line
			(start -0.508 -0.9398)
			(end -0.508 0.9398)
			(stroke
				(width 0.1524)
				(type default)
			)
			(layer "F.SilkS")
		)
		(fp_line
			(start 0.508 -0.9398)
			(end -0.508 -0.9398)
			(stroke
				(width 0.1524)
				(type default)
			)
			(layer "F.SilkS")
		)
		(fp_rect
			(start -0.508 0.9398)
			(end 0.508 -0.9398)
			(stroke
				(width 0)
				(type default)
			)
			(fill no)
			(layer "F.CrtYd")
		)
		(fp_rect
			(start -0.508 0.9398)
			(end 0.508 -0.9398)
			(stroke
				(width 0)
				(type default)
			)
			(fill no)
			(layer "F.Fab")
		)
		(pad "1" smd custom
			(at 0 -0.4445 270)
			(size 0.1397 0.1397)
			(layers "F.Cu" "F.Mask" "F.Paste")
			(net "P5VC")
			(options
				(clearance outline)
				(anchor circle)
			)
			(primitives
				(gr_poly
					(pts
						(arc
							(start -0.1778 -0.2794)
							(mid -0.249642 -0.249642)
							(end -0.2794 -0.1778)
						)
						(arc
							(start -0.2794 0.1778)
							(mid -0.249642 0.249642)
							(end -0.1778 0.2794)
						)
						(arc
							(start 0.1778 0.2794)
							(mid 0.249642 0.249642)
							(end 0.2794 0.1778)
						)
						(arc
							(start 0.2794 -0.1778)
							(mid 0.249642 -0.249642)
							(end 0.1778 -0.2794)
						)
					)
					(width 0)
					(fill yes)
				)
			)
		)
		(pad "2" smd custom
			(at 0 0.4445 270)
			(size 0.1397 0.1397)
			(layers "F.Cu" "F.Mask" "F.Paste")
			(net "DRIVE_ACT_10")
			(options
				(clearance outline)
				(anchor circle)
			)
			(primitives
				(gr_poly
					(pts
						(arc
							(start -0.1778 -0.2794)
							(mid -0.249642 -0.249642)
							(end -0.2794 -0.1778)
						)
						(arc
							(start -0.2794 0.1778)
							(mid -0.249642 0.249642)
							(end -0.1778 0.2794)
						)
						(arc
							(start 0.1778 0.2794)
							(mid 0.249642 0.249642)
							(end 0.2794 0.1778)
						)
						(arc
							(start 0.2794 -0.1778)
							(mid 0.249642 -0.249642)
							(end 0.1778 -0.2794)
						)
					)
					(width 0)
					(fill yes)
				)
			)
		)
	)
	(footprint ""
		(layer "F.Cu")
		(at 190.930784 -185.390028 -90)
		(property "Reference" "R155"
			(at 0 0 270)
			(layer "F.SilkS")
			(hide yes)
			(effects
				(font
					(size 1.27 1.27)
				)
			)
		)
		(property "Value" "0R2J-2-GP"
			(at 0.064008 -3.993896 270)
			(unlocked yes)
			(layer "F.Fab")
			(hide yes)
			(effects
				(font
					(size 1.016 1.016)
					(thickness 0.1524)
				)
			)
		)
		(property "Device Type" "R402H16"
			(at 0.064008 -5.517896 270)
			(unlocked yes)
			(layer "F.Fab")
			(hide yes)
			(effects
				(font
					(size 1.016 1.016)
					(thickness 0.1524)
				)
			)
		)
		(duplicate_pad_numbers_are_jumpers no)
		(fp_line
			(start -0.508 -0.9398)
			(end -0.508 0.9398)
			(stroke
				(width 0.1524)
				(type default)
			)
			(layer "F.SilkS")
		)
		(fp_line
			(start 0.508 -0.9398)
			(end -0.508 -0.9398)
			(stroke
				(width 0.1524)
				(type default)
			)
			(layer "F.SilkS")
		)
		(fp_rect
			(start -0.508 0.9398)
			(end 0.508 -0.9398)
			(stroke
				(width 0)
				(type default)
			)
			(fill no)
			(layer "F.CrtYd")
		)
		(fp_rect
			(start -0.508 0.9398)
			(end 0.508 -0.9398)
			(stroke
				(width 0)
				(type default)
			)
			(fill no)
			(layer "F.Fab")
		)
		(pad "1" smd custom
			(at 0 -0.4445 270)
			(size 0.1397 0.1397)
			(layers "F.Cu" "F.Mask" "F.Paste")
			(net "DRIVE_PWR3")
			(options
				(clearance outline)
				(anchor circle)
			)
			(primitives
				(gr_poly
					(pts
						(arc
							(start -0.1778 -0.2794)
							(mid -0.249642 -0.249642)
							(end -0.2794 -0.1778)
						)
						(arc
							(start -0.2794 0.1778)
							(mid -0.249642 0.249642)
							(end -0.1778 0.2794)
						)
						(arc
							(start 0.1778 0.2794)
							(mid 0.249642 0.249642)
							(end 0.2794 0.1778)
						)
						(arc
							(start 0.2794 -0.1778)
							(mid 0.249642 -0.249642)
							(end 0.1778 -0.2794)
						)
					)
					(width 0)
					(fill yes)
				)
			)
		)
		(pad "2" smd custom
			(at 0 0.4445 270)
			(size 0.1397 0.1397)
			(layers "F.Cu" "F.Mask" "F.Paste")
			(net "SW_PWR_HDD3")
			(options
				(clearance outline)
				(anchor circle)
			)
			(primitives
				(gr_poly
					(pts
						(arc
							(start -0.1778 -0.2794)
							(mid -0.249642 -0.249642)
							(end -0.2794 -0.1778)
						)
						(arc
							(start -0.2794 0.1778)
							(mid -0.249642 0.249642)
							(end -0.1778 0.2794)
						)
						(arc
							(start 0.1778 0.2794)
							(mid 0.249642 0.249642)
							(end 0.2794 0.1778)
						)
						(arc
							(start 0.2794 -0.1778)
							(mid 0.249642 -0.249642)
							(end 0.1778 -0.2794)
						)
					)
					(width 0)
					(fill yes)
				)
			)
		)
	)
	(footprint ""
		(layer "F.Cu")
		(at 212.724746 -479.6917 180)
		(property "Reference" "Q49"
			(at 0 0 180)
			(layer "F.SilkS")
			(hide yes)
			(effects
				(font
					(size 1.27 1.27)
				)
			)
		)
		(property "Value" "2N7002-11-GP"
			(at 0.127 -8.9662 180)
			(unlocked yes)
			(layer "F.Fab")
			(hide yes)
			(effects
				(font
					(size 1.016 1.016)
					(thickness 0.1524)
				)
			)
		)
		(property "Device Type" "SOT23DGS2D4H44"
			(at 0.127 -10.4902 180)
			(unlocked yes)
			(layer "F.Fab")
			(hide yes)
			(effects
				(font
					(size 1.016 1.016)
					(thickness 0.1524)
				)
			)
		)
		(duplicate_pad_numbers_are_jumpers no)
		(fp_line
			(start 1.651 1.778)
			(end 1.651 -1.778)
			(stroke
				(width 0.1524)
				(type default)
			)
			(layer "F.SilkS")
		)
		(fp_line
			(start 1.651 -1.778)
			(end -1.651 -1.778)
			(stroke
				(width 0.1524)
				(type default)
			)
			(layer "F.SilkS")
		)
		(fp_line
			(start -1.651 1.778)
			(end 1.651 1.778)
			(stroke
				(width 0.1524)
				(type default)
			)
			(layer "F.SilkS")
		)
		(fp_line
			(start -1.651 -1.778)
			(end -1.651 1.778)
			(stroke
				(width 0.1524)
				(type default)
			)
			(layer "F.SilkS")
		)
		(fp_poly
			(pts
				(xy -1.778 1.8796) (xy -1.778 -1.8796) (xy 1.778 -1.8796) (xy 1.778 1.8796)
			)
			(stroke
				(width 0)
				(type default)
			)
			(fill no)
			(layer "F.CrtYd")
		)
		(fp_poly
			(pts
				(xy -1.778 1.8796) (xy -1.778 -1.8796) (xy 1.778 -1.8796) (xy 1.778 1.8796)
			)
			(stroke
				(width 0)
				(type default)
			)
			(fill no)
			(layer "F.Fab")
		)
		(pad "D" smd custom
			(at 0 -0.9525 180)
			(size 0.1905 0.1905)
			(layers "F.Cu" "F.Mask" "F.Paste")
			(net "HDD0_LED_G")
			(options
				(clearance outline)
				(anchor circle)
			)
			(primitives
				(gr_poly
					(pts
						(arc
							(start -0.1778 0.5715)
							(mid -0.321484 0.511984)
							(end -0.381 0.3683)
						)
						(arc
							(start -0.381 -0.3683)
							(mid -0.321484 -0.511984)
							(end -0.1778 -0.5715)
						)
						(arc
							(start 0.1778 -0.5715)
							(mid 0.321484 -0.511984)
							(end 0.381 -0.3683)
						)
						(arc
							(start 0.381 0.3683)
							(mid 0.321484 0.511984)
							(end 0.1778 0.5715)
						)
					)
					(width 0)
					(fill yes)
				)
			)
		)
		(pad "G" smd custom
			(at -0.98425 0.9525 180)
			(size 0.1905 0.1905)
			(layers "F.Cu" "F.Mask" "F.Paste")
			(net "HDD0_LED_B")
			(options
				(clearance outline)
				(anchor circle)
			)
			(primitives
				(gr_poly
					(pts
						(arc
							(start -0.1778 0.5715)
							(mid -0.321484 0.511984)
							(end -0.381 0.3683)
						)
						(arc
							(start -0.381 -0.3683)
							(mid -0.321484 -0.511984)
							(end -0.1778 -0.5715)
						)
						(arc
							(start 0.1778 -0.5715)
							(mid 0.321484 -0.511984)
							(end 0.381 -0.3683)
						)
						(arc
							(start 0.381 0.3683)
							(mid 0.321484 0.511984)
							(end 0.1778 0.5715)
						)
					)
					(width 0)
					(fill yes)
				)
			)
		)
		(pad "S" smd custom
			(at 0.98425 0.9525 180)
			(size 0.1905 0.1905)
			(layers "F.Cu" "F.Mask" "F.Paste")
			(net "GND")
			(options
				(clearance outline)
				(anchor circle)
			)
			(primitives
				(gr_poly
					(pts
						(arc
							(start -0.1778 0.5715)
							(mid -0.321484 0.511984)
							(end -0.381 0.3683)
						)
						(arc
							(start -0.381 -0.3683)
							(mid -0.321484 -0.511984)
							(end -0.1778 -0.5715)
						)
						(arc
							(start 0.1778 -0.5715)
							(mid 0.321484 -0.511984)
							(end 0.381 -0.3683)
						)
						(arc
							(start 0.381 0.3683)
							(mid 0.321484 0.511984)
							(end 0.1778 0.5715)
						)
					)
					(width 0)
					(fill yes)
				)
			)
		)
	)
	(footprint ""
		(layer "F.Cu")
		(at 187.464446 -456.853036 90)
		(property "Reference" "R347"
			(at 0 0 90)
			(layer "F.SilkS")
			(hide yes)
			(effects
				(font
					(size 1.27 1.27)
				)
			)
		)
		(property "Value" "4K7R2J-2-GP"
			(at 0.064008 -3.993896 90)
			(unlocked yes)
			(layer "F.Fab")
			(hide yes)
			(effects
				(font
					(size 1.016 1.016)
					(thickness 0.1524)
				)
			)
		)
		(property "Device Type" "R402H16"
			(at 0.064008 -5.517896 90)
			(unlocked yes)
			(layer "F.Fab")
			(hide yes)
			(effects
				(font
					(size 1.016 1.016)
					(thickness 0.1524)
				)
			)
		)
		(duplicate_pad_numbers_are_jumpers no)
		(fp_line
			(start 0.508 -0.9398)
			(end -0.508 -0.9398)
			(stroke
				(width 0.1524)
				(type default)
			)
			(layer "F.SilkS")
		)
		(fp_line
			(start -0.508 -0.9398)
			(end -0.508 0.9398)
			(stroke
				(width 0.1524)
				(type default)
			)
			(layer "F.SilkS")
		)
		(fp_rect
			(start -0.508 0.9398)
			(end 0.508 -0.9398)
			(stroke
				(width 0)
				(type default)
			)
			(fill no)
			(layer "F.CrtYd")
		)
		(fp_rect
			(start -0.508 0.9398)
			(end 0.508 -0.9398)
			(stroke
				(width 0)
				(type default)
			)
			(fill no)
			(layer "F.Fab")
		)
		(pad "1" smd custom
			(at 0 -0.4445 90)
			(size 0.1397 0.1397)
			(layers "F.Cu" "F.Mask" "F.Paste")
			(net "P3V3")
			(options
				(clearance outline)
				(anchor circle)
			)
			(primitives
				(gr_poly
					(pts
						(arc
							(start -0.1778 -0.2794)
							(mid -0.249642 -0.249642)
							(end -0.2794 -0.1778)
						)
						(arc
							(start -0.2794 0.1778)
							(mid -0.249642 0.249642)
							(end -0.1778 0.2794)
						)
						(arc
							(start 0.1778 0.2794)
							(mid 0.249642 0.249642)
							(end 0.2794 0.1778)
						)
						(arc
							(start 0.2794 -0.1778)
							(mid 0.249642 -0.249642)
							(end 0.1778 -0.2794)
						)
					)
					(width 0)
					(fill yes)
				)
			)
		)
		(pad "2" smd custom
			(at 0 0.4445 90)
			(size 0.1397 0.1397)
			(layers "F.Cu" "F.Mask" "F.Paste")
			(net "EEPROM_A2")
			(options
				(clearance outline)
				(anchor circle)
			)
			(primitives
				(gr_poly
					(pts
						(arc
							(start -0.1778 -0.2794)
							(mid -0.249642 -0.249642)
							(end -0.2794 -0.1778)
						)
						(arc
							(start -0.2794 0.1778)
							(mid -0.249642 0.249642)
							(end -0.1778 0.2794)
						)
						(arc
							(start 0.1778 0.2794)
							(mid 0.249642 0.249642)
							(end 0.2794 0.1778)
						)
						(arc
							(start 0.2794 -0.1778)
							(mid 0.249642 -0.249642)
							(end 0.1778 -0.2794)
						)
					)
					(width 0)
					(fill yes)
				)
			)
		)
	)
	(footprint ""
		(layer "F.Cu")
		(at 57.864756 -481.104702)
		(property "Reference" "R177"
			(at 0 0 0)
			(layer "F.SilkS")
			(hide yes)
			(effects
				(font
					(size 1.27 1.27)
				)
			)
		)
		(property "Value" "220R3F-1-GP"
			(at -0.0254 -2.5146 0)
			(unlocked yes)
			(layer "F.Fab")
			(hide yes)
			(effects
				(font
					(size 1.016 1.016)
					(thickness 0.1524)
				)
			)
		)
		(property "Device Type" "R603H22"
			(at -0.0254 -4.0386 0)
			(unlocked yes)
			(layer "F.Fab")
			(hide yes)
			(effects
				(font
					(size 1.016 1.016)
					(thickness 0.1524)
				)
			)
		)
		(duplicate_pad_numbers_are_jumpers no)
		(fp_line
			(start -0.4826 0)
			(end -0.2032 0)
			(stroke
				(width 0.2032)
				(type default)
			)
			(layer "F.SilkS")
		)
		(fp_line
			(start 0.2032 0)
			(end 0.4826 0)
			(stroke
				(width 0.2032)
				(type default)
			)
			(layer "F.SilkS")
		)
		(fp_rect
			(start -0.5842 1.3335)
			(end 0.5842 -1.3335)
			(stroke
				(width 0)
				(type default)
			)
			(fill no)
			(layer "F.CrtYd")
		)
		(fp_rect
			(start -0.5842 1.3335)
			(end 0.5842 -1.3335)
			(stroke
				(width 0)
				(type default)
			)
			(fill no)
			(layer "F.Fab")
		)
		(pad "1" smd custom
			(at 0 -0.762)
			(size 0.2159 0.2159)
			(layers "F.Cu" "F.Mask" "F.Paste")
			(net "HDD_PRSNT_NET5")
			(options
				(clearance outline)
				(anchor circle)
			)
			(primitives
				(gr_poly
					(pts
						(arc
							(start -0.3302 -0.4318)
							(mid -0.402042 -0.402042)
							(end -0.4318 -0.3302)
						)
						(arc
							(start -0.4318 0.3302)
							(mid -0.402042 0.402042)
							(end -0.3302 0.4318)
						)
						(arc
							(start 0.3302 0.4318)
							(mid 0.402042 0.402042)
							(end 0.4318 0.3302)
						)
						(arc
							(start 0.4318 -0.3302)
							(mid 0.402042 -0.402042)
							(end 0.3302 -0.4318)
						)
					)
					(width 0)
					(fill yes)
				)
			)
		)
		(pad "2" smd custom
			(at 0 0.762)
			(size 0.2159 0.2159)
			(layers "F.Cu" "F.Mask" "F.Paste")
			(net "HDD_PRSNT5")
			(options
				(clearance outline)
				(anchor circle)
			)
			(primitives
				(gr_poly
					(pts
						(arc
							(start -0.3302 -0.4318)
							(mid -0.402042 -0.402042)
							(end -0.4318 -0.3302)
						)
						(arc
							(start -0.4318 0.3302)
							(mid -0.402042 0.402042)
							(end -0.3302 0.4318)
						)
						(arc
							(start 0.3302 0.4318)
							(mid 0.402042 0.402042)
							(end 0.4318 0.3302)
						)
						(arc
							(start 0.4318 -0.3302)
							(mid 0.402042 -0.402042)
							(end 0.3302 -0.4318)
						)
					)
					(width 0)
					(fill yes)
				)
			)
		)
	)
	(footprint ""
		(layer "F.Cu")
		(at 17.500092 -52.839874)
		(property "Reference" "LED15"
			(at 0 0 0)
			(layer "F.SilkS")
			(hide yes)
			(effects
				(font
					(size 1.27 1.27)
				)
			)
		)
		(property "Value" "LED-RB-4-GP"
			(at 5.88899 1.80848 0)
			(unlocked yes)
			(layer "F.Fab")
			(hide yes)
			(effects
				(font
					(size 1.016 1.016)
					(thickness 0.1524)
				)
			)
		)
		(property "Device Type" "LED1613-4PH20"
			(at 5.88899 0.28448 0)
			(unlocked yes)
			(layer "F.Fab")
			(hide yes)
			(effects
				(font
					(size 1.016 1.016)
					(thickness 0.1524)
				)
			)
		)
		(duplicate_pad_numbers_are_jumpers no)
		(fp_line
			(start -1.4478 -0.9652)
			(end 1.4478 -0.9652)
			(stroke
				(width 0.1524)
				(type default)
			)
			(layer "F.SilkS")
		)
		(fp_line
			(start -1.4478 0.9652)
			(end -1.4478 -0.9652)
			(stroke
				(width 0.1524)
				(type default)
			)
			(layer "F.SilkS")
		)
		(fp_line
			(start -1.4478 0.9652)
			(end -1.4478 -0.9652)
			(stroke
				(width 0.508)
				(type default)
			)
			(layer "F.SilkS")
		)
		(fp_line
			(start 1.4478 -0.9652)
			(end 1.4478 0.9652)
			(stroke
				(width 0.1524)
				(type default)
			)
			(layer "F.SilkS")
		)
		(fp_line
			(start 1.4478 0.9652)
			(end -1.4478 0.9652)
			(stroke
				(width 0.1524)
				(type default)
			)
			(layer "F.SilkS")
		)
		(fp_rect
			(start -0.8001 0.6477)
			(end 0.8001 -0.6477)
			(stroke
				(width 0)
				(type default)
			)
			(fill no)
			(layer "F.CrtYd")
		)
		(fp_poly
			(pts
				(xy -1.7018 1.2192) (xy -1.7018 -0.06223) (xy -0.8001 -0.06223) (xy -0.8001 0.6477) (xy 0.8001 0.6477)
				(xy 0.8001 -0.6477) (xy -0.8001 -0.6477) (xy -0.8001 -0.0635) (xy -1.7018 -0.0635) (xy -1.7018 -1.2192)
				(xy 1.7018 -1.2192) (xy 1.7018 1.2192)
			)
			(stroke
				(width 0)
				(type default)
			)
			(fill no)
			(layer "F.CrtYd")
		)
		(fp_rect
			(start -1.7018 1.2192)
			(end 1.7018 -1.2192)
			(stroke
				(width 0)
				(type default)
			)
			(fill no)
			(layer "F.Fab")
		)
		(pad "1" smd rect
			(at -0.73025 0.4064)
			(size 0.9144 0.6096)
			(layers "F.Cu" "F.Mask" "F.Paste")
			(net "DRV_ACT_NET14")
		)
		(pad "2" smd rect
			(at -0.73025 -0.4064)
			(size 0.9144 0.6096)
			(layers "F.Cu" "F.Mask" "F.Paste")
			(net "FLT_NET_HDD14")
		)
		(pad "3" smd rect
			(at 0.73025 -0.4064)
			(size 0.9144 0.6096)
			(layers "F.Cu" "F.Mask" "F.Paste")
			(net "FLT_HDD14")
		)
		(pad "4" smd rect
			(at 0.73025 0.4064)
			(size 0.9144 0.6096)
			(layers "F.Cu" "F.Mask" "F.Paste")
			(net "DRV_ACT_14")
		)
	)
	(footprint ""
		(layer "F.Cu")
		(at 6.095746 -499.5037 180)
		(property "Reference" "PR34"
			(at 0 0 180)
			(layer "F.SilkS")
			(hide yes)
			(effects
				(font
					(size 1.27 1.27)
				)
			)
		)
		(property "Value" "0R2J-2-GP"
			(at 0.064008 -3.993896 180)
			(unlocked yes)
			(layer "F.Fab")
			(hide yes)
			(effects
				(font
					(size 1.016 1.016)
					(thickness 0.1524)
				)
			)
		)
		(property "Device Type" "R402H16"
			(at 0.064008 -5.517896 180)
			(unlocked yes)
			(layer "F.Fab")
			(hide yes)
			(effects
				(font
					(size 1.016 1.016)
					(thickness 0.1524)
				)
			)
		)
		(duplicate_pad_numbers_are_jumpers no)
		(fp_line
			(start 0.508 -0.9398)
			(end -0.508 -0.9398)
			(stroke
				(width 0.1524)
				(type default)
			)
			(layer "F.SilkS")
		)
		(fp_line
			(start -0.508 -0.9398)
			(end -0.508 0.9398)
			(stroke
				(width 0.1524)
				(type default)
			)
			(layer "F.SilkS")
		)
		(fp_rect
			(start -0.508 0.9398)
			(end 0.508 -0.9398)
			(stroke
				(width 0)
				(type default)
			)
			(fill no)
			(layer "F.CrtYd")
		)
		(fp_rect
			(start -0.508 0.9398)
			(end 0.508 -0.9398)
			(stroke
				(width 0)
				(type default)
			)
			(fill no)
			(layer "F.Fab")
		)
		(pad "1" smd custom
			(at 0 -0.4445 180)
			(size 0.1397 0.1397)
			(layers "F.Cu" "F.Mask" "F.Paste")
			(net "P5VC_RF")
			(options
				(clearance outline)
				(anchor circle)
			)
			(primitives
				(gr_poly
					(pts
						(arc
							(start -0.1778 -0.2794)
							(mid -0.249642 -0.249642)
							(end -0.2794 -0.1778)
						)
						(arc
							(start -0.2794 0.1778)
							(mid -0.249642 0.249642)
							(end -0.1778 0.2794)
						)
						(arc
							(start 0.1778 0.2794)
							(mid 0.249642 0.249642)
							(end 0.2794 0.1778)
						)
						(arc
							(start 0.2794 -0.1778)
							(mid 0.249642 -0.249642)
							(end 0.1778 -0.2794)
						)
					)
					(width 0)
					(fill yes)
				)
			)
		)
		(pad "2" smd custom
			(at 0 0.4445 180)
			(size 0.1397 0.1397)
			(layers "F.Cu" "F.Mask" "F.Paste")
			(net "P5VC_AGND")
			(options
				(clearance outline)
				(anchor circle)
			)
			(primitives
				(gr_poly
					(pts
						(arc
							(start -0.1778 -0.2794)
							(mid -0.249642 -0.249642)
							(end -0.2794 -0.1778)
						)
						(arc
							(start -0.2794 0.1778)
							(mid -0.249642 0.249642)
							(end -0.1778 0.2794)
						)
						(arc
							(start 0.1778 0.2794)
							(mid 0.249642 0.249642)
							(end 0.2794 0.1778)
						)
						(arc
							(start 0.2794 -0.1778)
							(mid 0.249642 -0.249642)
							(end 0.1778 -0.2794)
						)
					)
					(width 0)
					(fill yes)
				)
			)
		)
	)
)
